# T6G (Grand Teton) — schematic netlist excerpt (pin names and nets, part order shuffled) for the footprints in the layout excerpt that follows; sources: Cadence DE-HDL packaged netlist, KiCad conversion of 04192023_DAF0TMB3IC0_F0TG_MB_C_brd_V02_OCP.brd

R3834  Q_RES  0 5% EMPTY  pkg 0402LF  page 135 : A = P12V_OCP_SFF_EN_R ; B = P12V_OCP_EN_1_R2
PR525  Q_RES  1.5 1% EMPTY  pkg 0402LF  page 215 : A = SW_PVDDCR_SOC_P1_SW1_RC ; B = GND

(kicad_pcb
	(version 20260206)
	(generator "pcbnew")
	(generator_version "10.0")
	(general
		(thickness 1.6)
		(legacy_teardrops no)
	)
	(paper "A4")
	(title_block
		(title "04192023_DAF0TMB3IC0_F0TG_MB_C_brd_V02_OCP.brd")
		(comment 1 "Grand Teton / footprints 2446-2447 of 8354")
	)
	(layers
		(0 "F.Cu" signal "TOP")
		(4 "In1.Cu" signal "GND")
		(6 "In2.Cu" signal "IN1")
		(8 "In3.Cu" signal "GND1")
		(10 "In4.Cu" signal "IN2")
		(12 "In5.Cu" signal "GND2")
		(14 "In6.Cu" signal "IN3")
		(16 "In7.Cu" signal "GND3")
		(18 "In8.Cu" signal "VCC")
		(20 "In9.Cu" signal "VCC1")
		(22 "In10.Cu" signal "GND4")
		(24 "In11.Cu" signal "IN4")
		(26 "In12.Cu" signal "GND5")
		(28 "In13.Cu" signal "IN5")
		(30 "In14.Cu" signal "GND6")
		(32 "In15.Cu" signal "IN6")
		(34 "In16.Cu" signal "GND7")
		(2 "B.Cu" signal "BOTTOM")
		(9 "F.Adhes" user "F.Adhesive")
		(11 "B.Adhes" user "B.Adhesive")
		(13 "F.Paste" user "Package Geometry/Pastemask Top")
		(15 "B.Paste" user "Package Geometry/Pastemask Bottom")
		(5 "F.SilkS" user "Ref Des/Silkscreen Top")
		(7 "B.SilkS" user "Ref Des/Silkscreen Bottom")
		(1 "F.Mask" user "Board Geometry/Soldermask Top")
		(3 "B.Mask" user "Board Geometry/Soldermask Bottom")
		(17 "Dwgs.User" user "User.Drawings")
		(19 "Cmts.User" user "User.Comments")
		(21 "Eco1.User" user "User.Eco1")
		(23 "Eco2.User" user "User.Eco2")
		(25 "Edge.Cuts" user "Board Geometry/Outline")
		(27 "Margin" user)
		(31 "F.CrtYd" user "Package Geometry/Place Bound Top")
		(29 "B.CrtYd" user "Package Geometry/Place Bound Bottom")
		(35 "F.Fab" user "Ref Des/Assembly Top")
		(33 "B.Fab" user "Ref Des/Assembly Bottom")
	)
	(footprint ""
		(layer "F.Cu")
		(at 444.733172 -32.173418 -90)
		(property "Reference" "R3834"
			(at 0 0 270)
			(layer "F.SilkS")
			(hide yes)
			(effects
				(font
					(size 1.27 1.27)
				)
			)
		)
		(property "Value" ""
			(at 0 0 270)
			(layer "F.Fab")
			(effects
				(font
					(size 1.27 1.27)
				)
			)
		)
		(duplicate_pad_numbers_are_jumpers no)
		(fp_line
			(start -0.7874 0.4064)
			(end -0.7874 -0.4064)
			(stroke
				(width 0.1524)
				(type default)
			)
			(layer "F.SilkS")
		)
		(fp_line
			(start 0.7874 0.4064)
			(end -0.7874 0.4064)
			(stroke
				(width 0.1524)
				(type default)
			)
			(layer "F.SilkS")
		)
		(fp_line
			(start -0.7874 -0.4064)
			(end 0.7874 -0.4064)
			(stroke
				(width 0.1524)
				(type default)
			)
			(layer "F.SilkS")
		)
		(fp_line
			(start 0.7874 -0.4064)
			(end 0.7874 0.4064)
			(stroke
				(width 0.1524)
				(type default)
			)
			(layer "F.SilkS")
		)
		(fp_line
			(start -0.67945 0.3048)
			(end -0.67945 -0.305054)
			(stroke
				(width 0.1)
				(type default)
			)
			(layer "F.Fab")
		)
		(fp_line
			(start -0.12065 0.3048)
			(end -0.67945 0.3048)
			(stroke
				(width 0.1)
				(type default)
			)
			(layer "F.Fab")
		)
		(fp_line
			(start 0.120396 0.3048)
			(end 0.120396 0.2794)
			(stroke
				(width 0.1)
				(type default)
			)
			(layer "F.Fab")
		)
		(fp_line
			(start 0.67945 0.3048)
			(end 0.120396 0.3048)
			(stroke
				(width 0.1)
				(type default)
			)
			(layer "F.Fab")
		)
		(fp_line
			(start -0.12065 0.2794)
			(end -0.12065 0.3048)
			(stroke
				(width 0.1)
				(type default)
			)
			(layer "F.Fab")
		)
		(fp_line
			(start 0.120396 0.2794)
			(end -0.12065 0.2794)
			(stroke
				(width 0.1)
				(type default)
			)
			(layer "F.Fab")
		)
		(fp_line
			(start -0.12065 -0.2794)
			(end 0.12065 -0.2794)
			(stroke
				(width 0.1)
				(type default)
			)
			(layer "F.Fab")
		)
		(fp_line
			(start 0.12065 -0.2794)
			(end 0.12065 -0.3048)
			(stroke
				(width 0.1)
				(type default)
			)
			(layer "F.Fab")
		)
		(fp_line
			(start 0.12065 -0.3048)
			(end 0.67945 -0.3048)
			(stroke
				(width 0.1)
				(type default)
			)
			(layer "F.Fab")
		)
		(fp_line
			(start 0.67945 -0.3048)
			(end 0.67945 0.3048)
			(stroke
				(width 0.1)
				(type default)
			)
			(layer "F.Fab")
		)
		(fp_line
			(start -0.67945 -0.305054)
			(end -0.12065 -0.305054)
			(stroke
				(width 0.1)
				(type default)
			)
			(layer "F.Fab")
		)
		(fp_line
			(start -0.12065 -0.305054)
			(end -0.12065 -0.2794)
			(stroke
				(width 0.1)
				(type default)
			)
			(layer "F.Fab")
		)
		(pad "1" smd circle
			(at -0.40005 0 270)
			(size 0 0)
			(layers "F.Cu" "F.Mask" "F.Paste")
			(net "P12V_OCP_SFF_EN_R")
		)
		(pad "2" smd circle
			(at 0.40005 0 270)
			(size 0 0)
			(layers "F.Cu" "F.Mask" "F.Paste")
			(net "P12V_OCP_EN_1_R2")
		)
	)
	(footprint ""
		(layer "F.Cu")
		(at 119.362728 -173.657768 -90)
		(property "Reference" "PR525"
			(at 0 0 270)
			(layer "F.SilkS")
			(hide yes)
			(effects
				(font
					(size 1.27 1.27)
				)
			)
		)
		(property "Value" ""
			(at 0 0 270)
			(layer "F.Fab")
			(effects
				(font
					(size 1.27 1.27)
				)
			)
		)
		(duplicate_pad_numbers_are_jumpers no)
		(fp_line
			(start -0.7874 0.4064)
			(end -0.7874 -0.4064)
			(stroke
				(width 0.1524)
				(type default)
			)
			(layer "F.SilkS")
		)
		(fp_line
			(start 0.7874 0.4064)
			(end -0.7874 0.4064)
			(stroke
				(width 0.1524)
				(type default)
			)
			(layer "F.SilkS")
		)
		(fp_line
			(start -0.7874 -0.4064)
			(end 0.7874 -0.4064)
			(stroke
				(width 0.1524)
				(type default)
			)
			(layer "F.SilkS")
		)
		(fp_line
			(start 0.7874 -0.4064)
			(end 0.7874 0.4064)
			(stroke
				(width 0.1524)
				(type default)
			)
			(layer "F.SilkS")
		)
		(fp_line
			(start -0.67945 0.3048)
			(end -0.67945 -0.305054)
			(stroke
				(width 0.1)
				(type default)
			)
			(layer "F.Fab")
		)
		(fp_line
			(start -0.12065 0.3048)
			(end -0.67945 0.3048)
			(stroke
				(width 0.1)
				(type default)
			)
			(layer "F.Fab")
		)
		(fp_line
			(start 0.120396 0.3048)
			(end 0.120396 0.2794)
			(stroke
				(width 0.1)
				(type default)
			)
			(layer "F.Fab")
		)
		(fp_line
			(start 0.67945 0.3048)
			(end 0.120396 0.3048)
			(stroke
				(width 0.1)
				(type default)
			)
			(layer "F.Fab")
		)
		(fp_line
			(start -0.12065 0.2794)
			(end -0.12065 0.3048)
			(stroke
				(width 0.1)
				(type default)
			)
			(layer "F.Fab")
		)
		(fp_line
			(start 0.120396 0.2794)
			(end -0.12065 0.2794)
			(stroke
				(width 0.1)
				(type default)
			)
			(layer "F.Fab")
		)
		(fp_line
			(start -0.12065 -0.2794)
			(end 0.12065 -0.2794)
			(stroke
				(width 0.1)
				(type default)
			)
			(layer "F.Fab")
		)
		(fp_line
			(start 0.12065 -0.2794)
			(end 0.12065 -0.3048)
			(stroke
				(width 0.1)
				(type default)
			)
			(layer "F.Fab")
		)
		(fp_line
			(start 0.12065 -0.3048)
			(end 0.67945 -0.3048)
			(stroke
				(width 0.1)
				(type default)
			)
			(layer "F.Fab")
		)
		(fp_line
			(start 0.67945 -0.3048)
			(end 0.67945 0.3048)
			(stroke
				(width 0.1)
				(type default)
			)
			(layer "F.Fab")
		)
		(fp_line
			(start -0.67945 -0.305054)
			(end -0.12065 -0.305054)
			(stroke
				(width 0.1)
				(type default)
			)
			(layer "F.Fab")
		)
		(fp_line
			(start -0.12065 -0.305054)
			(end -0.12065 -0.2794)
			(stroke
				(width 0.1)
				(type default)
			)
			(layer "F.Fab")
		)
		(pad "1" smd circle
			(at -0.40005 0 270)
			(size 0 0)
			(layers "F.Cu" "F.Mask" "F.Paste")
			(net "SW_PVDDCR_SOC_P1_SW1_RC")
		)
		(pad "2" smd circle
			(at 0.40005 0 270)
			(size 0 0)
			(layers "F.Cu" "F.Mask" "F.Paste")
			(net "GND")
		)
	)
)
